FILE_TYPE = MULTI_PHYS_TABLE;

PART 'CONN_HDR_2X6_F_S_SMT'
CLASS=IO

{========================================================================================}
:CLS_PN          | VALUE                  = JEDEC_TYPE                   | ALT_SYMBOLS                    | DESCRIPTION                                  | CPN_STATUS ;
{========================================================================================}
 'G200-11795-01' | 'ZP90-03503-1221'      = 'S_F_H_2X6_S_P050'           | '(S_F_H_2X6_S_P050)'           | 'CON,12P,2X6,FEMALE HEADER,V/T,1.27,SMT'     | ''        
 'G200-12513-01' | '87832-1220'           = 'S_M_H_2X6_NP2_S_P0787_H307' | '(S_M_H_2X6_NP2_S_P0787_H307)' | 'CON,12P,2*6,2MM PITCH,SMT'                  | ''        
 'G200-12597-01' | '878325522'            = 'S_M_H_2X6_NP2_S_P0787_H307' | '(S_M_H_2X6_NP2_S_P0787_H307)' | 'CON,12P,2*6,2MM PITCH,SMT'                  | ''        
 'G200-13133-01' | 'SMH-106-02-L-D-TR'    = 'S_F_H_2X6_RA_P100'          | '(S_F_H_2X6_RA_P100)'          | 'CON,12P,2X6,RCPT DOUBLE ROW,2.54MM,SMT,R/A' | ''        

END_PART

END.

